FILE_TYPE = CONNECTIVITY;
{Allegro Design Entry HDL 16.6-p007 (v16-6-112F) 10/10/2012}
"PAGE_NUMBER" = 201;
0"NC";
1"P3V3_STBY\g";
2"P3V3_STBY\g";
3"P3V3_STBY\g";
4"GND\g";
5"GND\g";
6"PVCCIO_CPU0\g";
7"GND\g";
8"GND\g";
9"GND\g";
10"GND\g";
11"GND\g";
12"GND\g";
13"GND\g";
14"PVCCIO_CPU0\g";
15"VR_FET_SW_P12V_STBY_PVCCIN_CPU0\g";
16"GND\g";
17"GND\g";
18"GND\g";
19"GND\g";
20"VR_PVCCIN_CPU0_VD12";
21"VSENSE_PVSA_CPU0_P";
22"VSENSE_PVCCIN_CPU0_P";
23"ISENSE_PVCCIN_CPU0_PH5_IMON";
24"ISENSE_PVCCIN_CPU0_PH3_IMON";
25"ISENSE_PVCCIN_CPU0_PH2_IMON";
26"ISENSE_PVCCIN_CPU0_PH1_IMON";
27"VR_PVCCIN_CPU0_AIREF2";
28"VR_PVCCIN_CPU0_AIREF1";
29"VSENSE_PVCCIN_CPU0_AVSP";
30"A_TSENSE_PVSA_CPU0";
31"TP_PVCCIN_CPU0_RESET";
32"VR_PVCCIN_CPU0_XADDR1"VOLTAGE"3.3";
33"ISENSE_PVSA_CPU0_IMON";
34"VR_PVSA_CPU0_BIREF1";
35"VR_PVCCIN_CPU0_XADDR2"VOLTAGE"3.3";
36"FM_PVCCIN_PVCCSA_CPU0_EN_LVC1";
37"VR_PVCCIN_CPU0_VD12";
38"VR_PVCCIN_CPU0_AIREF5";
39"VR_PVCCIN_CPU0_AIREF4";
40"VR_PVCCIN_CPU0_AIREF3";
41"VSENSE_PVSA_CPU0_BVSP";
42"VR_PVCCIN_CPU0_AVINSEN"VOLTAGE"0.8";
43"PVCCIN_PVSA_CPU0_IINSEN"VOLTAGE"+3.3V";
44"A_TSENSE_PVCCIN_CPU0";
45"VSENSE_PVSA_CPU0_N";
46"VSENSE_PVCCIN_CPU0_N";
47"TP_PVCCIN_CPU0_AISEN6";
48"TP_PVCCIN_CPU0_AIREF6";
49"SVID_VCLK_PVCCIN_CPU0";
50"SVID_CLK0_CPU0_R";
51"VR_PVCCIN_CPU0_VREN"VOLTAGE"3.3";
52"VR_PVCCIN_CPU0_AVINSEN"VOLTAGE"0.8";
53"VR_PVCCIN_CPU0_VDD"VOLTAGE"3.3";
54"SVID_VDIO_PVCCIN_CPU0";
55"TP_PVCCIN_CPU0_APWM6";
56"TP_PVCCIN_CPU0_FAULT1_20";
57"SVID_VALERT_VCCIN_CPU0";
58"TP_PVCCIN_CPU0_GP1";
59"IRQ_PVCCIN_CPU0_VRHOT_LVC3_R_N";
60"PU_VR_PVCCIN_CPU0_IMON";
61"VR_PVCCIN_CPU0_PWM1"VOLTAGE"3.6";
62"VR_PVSA_CPU0_PWM";
63"VR_PVCCIN_CPU0_PWM3"VOLTAGE"3.6";
64"VR_PVCCIN_CPU0_VD12";
65"IRQ_PVCCIN_CPU0_VRHOT_LVC3_N";
66"VR_PVCCIN_CPU0_PWM5"VOLTAGE"3.6";
67"VR_PVCCIN_CPU0_PWM4"VOLTAGE"3.6";
68"VR_PVCCIN_CPU0_PWM2"VOLTAGE"3.6";
69"PWRGD_PVSA_CPU0_R";
70"SMB_VR_SDA_R";
71"SMB_VR_SCL_R";
72"VR_PVCCIN_CPU0_VD12";
73"SMB_VR_STBY_LVC3_SDA";
74"SMB_VR_STBY_LVC3_SCL";
75"PWRGD_PVSA_CPU0";
76"SVID_ALERT0_CPU0_R_N";
77"SVID_DIO0_CPU0_R";
78"FM_PVCCIN_CPU0_PWR_IN_ALERT_N";
79"VR_VRRDY_PVCCIN_CPU0"VOLTAGE"3.3";
80"PWRGD_PVCCIN_CPU0";
81"PU_VR_PVCCIN_CPU0_FLT1_SMBALT_N_IMON";
82"ISENSE_PVCCIN_CPU0_PH4_IMON";
%"RES"
"2","(-1100,2000)","0","mstr_discrete","I102";
;
CDS_SEC"1"
$SEC"1"
CDS_LOCATION"R6P32"
ROOM"PVCCIN_CPU0_VR"
CDS_LIB"mstr_discrete"
LOCATION"R6P32"
VALUE"2.0K"
TOLERANCE"1%"
MATERIAL"EMPTY"
PART_NUMBER"G21796-001"
PACK_TYPE"0402"
WATTAGE"1/16W";
"A"
$PN"1"3;
"B"
$PN"2"73;
%"RES"
"2","(-850,2000)","0","mstr_discrete","I103";
;
CDS_SEC"1"
$SEC"1"
CDS_LOCATION"R6P37"
ROOM"PVCCIN_CPU0_VR"
CDS_LIB"mstr_discrete"
LOCATION"R6P37"
VALUE"2.0K"
TOLERANCE"1%"
MATERIAL"EMPTY"
PART_NUMBER"G21796-001"
PACK_TYPE"0402"
WATTAGE"1/16W";
"A"
$PN"1"3;
"B"
$PN"2"74;
%"RES"
"1","(-6675,2525)","0","mstr_discrete","I109";
;
CDS_SEC"1"
SEC_TYPE"0402"
SEC"1"
CDS_LOCATION"R4E8"
ROOM"PVCCIN_CPU0_VR"
CDS_LIB"mstr_discrete"
LOCATION"R4E8"
PART_NUMBER"G21796-066"
TOLERANCE"1%"
MATERIAL"CHIP"
NO_XNET_CONNECTION"1"
VALUE"10.0"
PACK_TYPE"0402"
WATTAGE"1/16W";
"B"
$PN"2"29;
"A"
$PN"1"22;
%"RES"
"1","(-6250,2075)","0","mstr_discrete","I110";
;
CDS_SEC"1"
SEC_TYPE"0402"
CDS_LIB"mstr_discrete"
ROOM"PVCCIN_CPU0_VR"
SEC"1"
CDS_LOCATION"R4D39"
PART_NUMBER"G21796-066"
MATERIAL"CHIP"
NO_XNET_CONNECTION"1"
LOCATION"R4D39"
PACK_TYPE"0402"
VALUE"10.0"
TOLERANCE"1%"
WATTAGE"1/16W";
"B"
$PN"2"41;
"A"
$PN"1"21;
%"RES"
"2","(-3050,4125)","2","mstr_discrete","I111";
;
CDS_SEC"1"
CDS_LIB"mstr_discrete"
SEC_TYPE"0402"
SEC"1"
CDS_LOCATION"R4E3"
ROOM"PVCCIN_CPU0_VR"
LOCATION"R4E3"
VALUE"1.00K"
TOLERANCE"1%"
WATTAGE"1/16W"
PACK_TYPE"0402"
MATERIAL"CHIP"
PART_NUMBER"G21796-026";
"A"
$PN"1"2;
"B"
$PN"2"59;
%"P3V3_STBY"
"1","(-4250,4600)","0","mstr_symbols","I112";
;
SIZE"1B"
CDS_LIB"mstr_symbols"
VOLTAGE"3.3V"
BODY_TYPE"PLUMBING"
HDL_POWER"P3V3_STBY";
"G\NAC"1;
%"P3V3_STBY"
"1","(-3050,4550)","0","mstr_symbols","I113";
;
SIZE"1B"
CDS_LIB"mstr_symbols"
VOLTAGE"3.3V"
BODY_TYPE"PLUMBING"
HDL_POWER"P3V3_STBY";
"G\NAC"2;
%"P3V3_STBY"
"1","(-375,2325)","0","mstr_symbols","I115";
;
VOLTAGE"3.3V"
CDS_LIB"mstr_symbols"
SIZE"1B"
BODY_TYPE"PLUMBING"
HDL_POWER"P3V3_STBY";
"G\NAC"3;
%"RES"
"2","(-1575,4200)","0","mstr_discrete","I116";
;
CDS_SEC"1"
CDS_LOCATION"R4E20"
SEC_TYPE"0402"
SEC"1"
ROOM"PVCCIN_CPU0_VR"
CDS_LIB"mstr_discrete"
MATERIAL"EMPTY"
LOCATION"R4E20"
VALUE"2.26K"
WATTAGE"1/16W"
TOLERANCE"1.0%"
PART_NUMBER"G21796-311"
PACK_TYPE"0402";
"A"
$PN"1"2;
"B"
$PN"2"81;
%"RES"
"2","(-4400,925)","0","mstr_discrete","I120";
;
CDS_SEC"1"
SEC_TYPE"0402"
SEC"1"
CDS_LOCATION"R6P27"
ROOM"PVCCIN_CPU0_VR"
CDS_LIB"mstr_discrete"
PART_NUMBER"G21796-082"
LOCATION"R6P27"
VALUE"4.02K"
TOLERANCE"1%"
PACK_TYPE"0402"
MATERIAL"CHIP"
WATTAGE"1/16W";
"A"
$PN"1"35;
"B"
$PN"2"12;
%"RES"
"2","(-4725,900)","0","mstr_discrete","I121";
;
CDS_SEC"1"
ROOM"PVCCIN_CPU0_VR"
CDS_LOCATION"R6P28"
SEC"1"
SEC_TYPE"0402"
CDS_LIB"mstr_discrete"
LOCATION"R6P28"
PART_NUMBER"G21796-082"
VALUE"4.02K"
PACK_TYPE"0402"
MATERIAL"CHIP"
WATTAGE"1/16W"
TOLERANCE"1%";
"A"
$PN"1"32;
"B"
$PN"2"13;
%"CONN3_C95678002"
"1","(-3150,825)","0","mstr_conn","I122";
;
CDS_SEC"1"
PACK_TYPE"PIP"
SEC_TYPE"PIP"
BOM_COST"SM_CONTROLLER"
CDS_LOCATION"J8D4"
ROOM"SMBUS"
SEC"1"
CDS_LIB"mstr_conn"
PART_NUMBER"C95678-002"
LOCATION"J8D4"
MATERIAL"CONN";
"IO1 \B"
$PN"1"73;
"IO2 \B"
$PN"2"4;
"IO3 \B"
$PN"3"74;
%"GND"
"1","(-2900,775)","0","mstr_symbols","I123";
;
VOLTAGE"0"
CDS_LIB"mstr_symbols"
SIZE"1B"
BODY_TYPE"PLUMBING"
HDL_POWER"GND";
"A\NAC"4;
%"RES"
"1","(-1125,3325)","0","mstr_discrete","I124";
;
$SEC"1"
CDS_SEC"1"
CDS_LOCATION"R4D63"
ROOM"PVCCIN_CPU0_VR"
CDS_LIB"mstr_discrete"
PACK_TYPE"0402"
PART_NUMBER"G21796-250"
TOLERANCE"1.0%"
MATERIAL"CHIP"
LOCATION"R4D63"
VALUE"22.1"
WATTAGE"1/16W";
"B"
$PN"2"80;
"A"
$PN"1"79;
%"CAP"
"1","(-1450,2075)","0","mstr_discrete","I125";
;
CDS_SEC"1"
ROOM"PVCCIN_CPU0_VR"
SEC_TYPE"0402LF"
CDS_LOCATION"C4D42"
SEC"1"
CDS_LIB"mstr_discrete"
LOCATION"C4D42"
VALUE"1000PF"
VOLTAGE"50V"
TOLERANCE"10%"
PART_NUMBER"A36096-046"
PACK_TYPE"0402LF"
MATERIAL"X7R";
"A"
$PN"1"79;
"B"
$PN"2"5;
%"GND"
"1","(-1450,1850)","0","mstr_symbols","I126";
;
SIZE"1B"
VOLTAGE"0"
CDS_LIB"mstr_symbols"
ROOM"PVCCIN_CPU0_VR"
BODY_TYPE"PLUMBING"
HDL_POWER"GND";
"A\NAC"5;
%"RES"
"1","(-1800,2675)","0","mstr_discrete","I127";
;
CDS_SEC"1"
SEC_TYPE"0402"
SEC"1"
CDS_LIB"mstr_discrete"
CDS_LOCATION"R4D65"
MATERIAL"CHIP"
PACK_TYPE"0402"
LOCATION"R4D65"
PART_NUMBER"G21796-074"
TOLERANCE"1%"
VALUE"33.2"
WATTAGE"1/16W";
"B"
$PN"2"75;
"A"
$PN"1"69;
%"RES"
"1","(-2400,2975)","0","mstr_discrete","I128";
;
CDS_SEC"1"
SEC_TYPE"0402"
SEC"1"
CDS_LIB"mstr_discrete"
CDS_LOCATION"R6P45"
PACK_TYPE"0402"
PART_NUMBER"G21796-074"
MATERIAL"CHIP"
TOLERANCE"1%"
LOCATION"R6P45"
VALUE"33.2"
WATTAGE"1/16W";
"B"
$PN"2"65;
"A"
$PN"1"59;
%"RES"
"1","(-5100,2225)","0","mstr_discrete","I131";
;
CDS_SEC"1"
CDS_LIB"mstr_discrete"
ROOM"PVCCIN_CPU0_VR"
SEC"1"
SEC_TYPE"0402"
CDS_LOCATION"R6P18"
PACK_TYPE"0402"
MATERIAL"CHIP"
LOCATION"R6P18"
PART_NUMBER"G21497-005"
TOLERANCE"5%"
VALUE"0.0"
WATTAGE"1/16W";
"B"
$PN"2"51;
"A"
$PN"1"36;
%"RES"
"2","(-4775,4350)","0","mstr_discrete","I132";
;
BOM_COST"SM_CONTROLLER"
$SEC"1"
CDS_SEC"1"
CDS_LOCATION"R6P16"
ROOM"BMC"
CDS_LIB"mstr_discrete"
LOCATION"R6P16"
PART_NUMBER"G21796-026"
VALUE"1.00K"
WATTAGE"1/16W"
TOLERANCE"1%"
PACK_TYPE"0402"
MATERIAL"CHIP";
"A"
$PN"1"14;
"B"
$PN"2"51;
%"RES"
"2","(-6475,3625)","0","mstr_discrete","I139";
;
CDS_SEC"1"
SEC_TYPE"0402"
SEC"1"
CDS_LOCATION"R6P42"
ROOM"PVCCIN_CPU0_VR"
CDS_LIB"mstr_discrete"
LOCATION"R6P42"
VALUE"0.0"
TOLERANCE"5%"
WATTAGE"1/16W"
PACK_TYPE"0402"
MATERIAL"CHIP"
PART_NUMBER"G21497-005";
"A"
$PN"1"37;
"B"
$PN"2"27;
%"RES"
"2","(-6000,3625)","0","mstr_discrete","I147";
;
CDS_SEC"1"
SEC_TYPE"0402"
SEC"1"
CDS_LOCATION"R6P38"
CDS_LIB"mstr_discrete"
ROOM"PVCCIN_CPU0_VR"
LOCATION"R6P38"
VALUE"0.0"
WATTAGE"1/16W"
TOLERANCE"5%"
MATERIAL"CHIP"
PART_NUMBER"G21497-005"
PACK_TYPE"0402";
"A"
$PN"1"37;
"B"
$PN"2"40;
%"RES"
"2","(-5575,3625)","0","mstr_discrete","I148";
;
CDS_SEC"1"
SEC"1"
SEC_TYPE"0402"
CDS_LOCATION"R6P34"
ROOM"PVCCIN_CPU0_VR"
CDS_LIB"mstr_discrete"
WATTAGE"1/16W"
TOLERANCE"5%"
VALUE"0.0"
LOCATION"R6P34"
MATERIAL"CHIP"
PART_NUMBER"G21497-005"
PACK_TYPE"0402";
"A"
$PN"1"37;
"B"
$PN"2"39;
%"RES"
"2","(-5175,3625)","0","mstr_discrete","I149";
;
CDS_SEC"1"
SEC_TYPE"0402"
SEC"1"
CDS_LOCATION"R6P30"
ROOM"PVCCIN_CPU0_VR"
CDS_LIB"mstr_discrete"
LOCATION"R6P30"
PART_NUMBER"G21497-005"
VALUE"0.0"
TOLERANCE"5%"
MATERIAL"CHIP"
WATTAGE"1/16W"
PACK_TYPE"0402";
"A"
$PN"1"37;
"B"
$PN"2"38;
%"RES"
"2","(-6850,3625)","0","mstr_discrete","I150";
;
CDS_SEC"1"
SEC"1"
SEC_TYPE"0402"
CDS_LOCATION"R6P43"
ROOM"PVCCIN_CPU0_VR"
CDS_LIB"mstr_discrete"
LOCATION"R6P43"
WATTAGE"1/16W"
TOLERANCE"5%"
VALUE"0.0"
PART_NUMBER"G21497-005"
PACK_TYPE"0402"
MATERIAL"CHIP";
"A"
$PN"1"37;
"B"
$PN"2"28;
%"RES"
"1","(-6375,1350)","0","mstr_discrete","I154";
;
CDS_SEC"1"
SEC"1"
SEC_TYPE"0402"
CDS_LIB"mstr_discrete"
ROOM"PVCCIN_CPU0_VR"
CDS_LOCATION"R6P29"
MATERIAL"CHIP"
PACK_TYPE"0402"
LOCATION"R6P29"
PART_NUMBER"G21497-005"
TOLERANCE"5%"
WATTAGE"1/16W"
VALUE"0.0";
"B"
$PN"2"34;
"A"
$PN"1"20;
%"PXE1610B"
"1","(-3800,2575)","0","mstr_controller","I155";
;
CDS_LMAN_SYM_OUTLINE"-400,900,400,-900"
CDS_LIB"mstr_controller"
$SEC"1"
CDS_SEC"1"
PACK_TYPE"QFN"
CDS_LOCATION"EU4D4"
LOCATION"EU4D4"
PART_NUMBER"H79206-001"
MATERIAL"IC";
"MP4"
$PN"40"56;
"MP3"
$PN"39"60;
"MP2"
$PN"20"81;
"MP1"
$PN"16"58;
"MP0"
$PN"15"69;
"AVREN"
$PN"12"51;
"AVRRDY"
$PN"11"79;
"VD12"
$PN"48"64;
"IINSEN"
$PN"46"43;
"VINSEN"
$PN"45"42;
"BVREF"
$PN"36"45;
"BVSEN"
$PN"35"41;
"AVREF"
$PN"22"46;
"AVSEN"
$PN"21"29;
"VALRT_N \B"
$PN"19"57;
"PINALRT_N \B"
$PN"14"78;
"VRHOT_N \B"
$PN"13"59;
"BIREF1"
$PN"37"34;
"BISEN1"
$PN"38"33;
"BTSEN"
$PN"42"30;
"VDD"
$PN"47"53;
"AIREF1"
$PN"23"28;
"AISEN1"
$PN"24"26;
"ATSEN"
$PN"43"44;
"AIREF2"
$PN"25"27;
"AISEN2"
$PN"26"25;
"XADDR2"
$PN"41"35;
"AIREF3"
$PN"27"40;
"AISEN3"
$PN"28"24;
"XADDR1"
$PN"44"32;
"AIREF4"
$PN"29"39;
"AISEN4"
$PN"30"82;
"AIREF5"
$PN"31"38;
"AISEN5"
$PN"32"23;
"AIREF6"
$PN"33"48;
"AISEN6"
$PN"34"47;
"RESET_N \B"
$PN"10"31;
"VDIO"
$PN"18"54;
"VCLK"
$PN"17"49;
"SCL"
$PN"9"71;
"SDA"
$PN"8"70;
"APWM6"
$PN"2"55;
"APWM5"
$PN"3"66;
"APWM4"
$PN"4"67;
"APWM3"
$PN"5"63;
"APWM2"
$PN"6"68;
"APWM1"
$PN"7"61;
"BPWM1"
$PN"1"62;
"THPAD"
$PN"49"9;
%"PVCCIO_CPU0"
"1","(-1275,3950)","0","mstr_symbols","I18";
;
CDS_LIB"mstr_symbols"
VOLTAGE"1.1V"
BODY_TYPE"PLUMBING"
HDL_POWER"PVCCIO_CPU0";
"G\NAC"6;
%"RES"
"2","(-1925,4100)","0","mstr_discrete","I19";
;
CDS_SEC"1"
SEC"1"
SEC_TYPE"0402"
CDS_LOCATION"R4E4"
CDS_LIB"mstr_discrete"
ROOM"PVCCIN_CPU0_VR"
MATERIAL"CHIP"
LOCATION"R4E4"
VALUE"2.26K"
TOLERANCE"1.0%"
WATTAGE"1/16W"
PART_NUMBER"G21796-311"
PACK_TYPE"0402";
"A"
$PN"1"2;
"B"
$PN"2"78;
%"RES"
"2","(-1275,3750)","0","mstr_discrete","I20";
;
CDS_SEC"1"
SEC"1"
SEC_TYPE"0402"
ROOM"PVCCIN_CPU0_VR"
CDS_LOCATION"R4E10"
CDS_LIB"mstr_discrete"
PART_NUMBER"G21796-017"
LOCATION"R4E10"
VALUE"100.0"
TOLERANCE"1%"
MATERIAL"CHIP"
WATTAGE"1/16W"
PACK_TYPE"0402";
"A"
$PN"1"6;
"B"
$PN"2"77;
%"RES"
"2","(-2075,3750)","0","mstr_discrete","I22";
;
CDS_SEC"1"
SEC_TYPE"0402"
SEC"1"
CDS_LOCATION"R4D31"
WATTAGE"1/16W"
ROOM"PVCCIN_CPU0_VR"
CDS_LIB"mstr_discrete"
PART_NUMBER"G21796-311"
LOCATION"R4D31"
VALUE"2.26K"
TOLERANCE"1.0%"
PACK_TYPE"0402"
MATERIAL"EMPTY";
"A"
$PN"1"2;
"B"
$PN"2"60;
%"RES"
"2","(-2500,3925)","0","mstr_discrete","I25";
;
CDS_SEC"1"
SEC_TYPE"0402"
SEC"1"
ROOM"PVCCIN_CPU0_VR"
CDS_LIB"mstr_discrete"
CDS_LOCATION"R4D58"
PART_NUMBER"G21796-026"
WATTAGE"1/16W"
MATERIAL"CHIP"
TOLERANCE"1%"
VALUE"1.00K"
LOCATION"R4D58"
PACK_TYPE"0402";
"A"
$PN"1"2;
"B"
$PN"2"79;
%"RES"
"1","(-2025,2875)","0","mstr_discrete","I26";
;
CDS_SEC"1"
CDS_LIB"mstr_discrete"
SEC_TYPE"0402"
SEC"1"
CDS_LOCATION"R4D67"
ROOM"PVCCIN_CPU0_VR"
PACK_TYPE"0402"
MATERIAL"CHIP"
LOCATION"R4D67"
PART_NUMBER"G21497-005"
TOLERANCE"5%"
VALUE"0.0"
WATTAGE"1/16W";
"B"
$PN"2"76;
"A"
$PN"1"57;
%"RES"
"2","(-2775,3925)","2","mstr_discrete","I27";
;
CDS_SEC"1"
ROOM"PVCCIN_CPU0_VR"
SEC"1"
SEC_TYPE"0402"
CDS_LIB"mstr_discrete"
CDS_LOCATION"R4E5"
PACK_TYPE"0402"
MATERIAL"CHIP"
WATTAGE"1/16W"
TOLERANCE"1%"
LOCATION"R4E5"
VALUE"1.00K"
PART_NUMBER"G21796-026";
"A"
$PN"1"2;
"B"
$PN"2"69;
%"RES"
"1","(-1900,1775)","0","mstr_discrete","I28";
;
CDS_SEC"1"
SEC_TYPE"0402"
SEC"1"
CDS_LOCATION"R4D50"
ROOM"PVCCIN_CPU0_VR"
CDS_LIB"mstr_discrete"
PACK_TYPE"0402"
MATERIAL"CHIP"
LOCATION"R4D50"
TOLERANCE"5%"
PART_NUMBER"G21497-005"
VALUE"0.0"
WATTAGE"1/16W";
"B"
$PN"2"73;
"A"
$PN"1"70;
%"GND"
"1","(-1475,675)","0","mstr_symbols","I29";
;
VOLTAGE"0"
SIZE"1B"
CDS_LIB"mstr_symbols"
ROOM"PVCCIN_CPU0_VR"
BODY_TYPE"PLUMBING"
HDL_POWER"GND";
"A\NAC"7;
%"CAP_A"
"1","(-1475,1000)","0","dev_discrete","I30";
;
SEC_TYPE"0402V"
SEC"1"
ROOM"PVCCIN_CPU0_VR"
CDS_SEC"1"
CDS_LOCATION"C4D25"
CDS_LIB"dev_discrete"
LOCATION"C4D25"
VALUE"1.0UF"
VOLTAGE"6.3V"
PART_NUMBER"D97712-004"
PACK_TYPE"0402V"
MATERIAL"X6S"
TOLERANCE"10%";
"B"
$PN"2"7;
"A"
$PN"1"72;
%"RES"
"1","(-1900,1525)","0","mstr_discrete","I31";
;
CDS_SEC"1"
CDS_LOCATION"R4D53"
SEC"1"
SEC_TYPE"0402"
ROOM"PVCCIN_CPU0_VR"
CDS_LIB"mstr_discrete"
LOCATION"R4D53"
PACK_TYPE"0402"
MATERIAL"CHIP"
TOLERANCE"5%"
PART_NUMBER"G21497-005"
VALUE"0.0"
WATTAGE"1/16W";
"B"
$PN"2"74;
"A"
$PN"1"71;
%"CAP_A"
"1","(-1875,1000)","0","dev_discrete","I32";
;
ROOM"PVCCIN_CPU0_VR"
CDS_LOCATION"C4D26"
CDS_SEC"1"
SEC_TYPE"0402V"
SEC"1"
CDS_LIB"dev_discrete"
LOCATION"C4D26"
VALUE"0.1UF"
VOLTAGE"16V"
PART_NUMBER"A36096-030"
TOLERANCE"10%"
PACK_TYPE"0402V"
MATERIAL"X7R";
"B"
$PN"2"8;
"A"
$PN"1"72;
%"GND"
"1","(-1875,800)","0","mstr_symbols","I33";
;
CDS_LIB"mstr_symbols"
VOLTAGE"0"
SIZE"1B"
ROOM"PVCCIN_CPU0_VR"
BODY_TYPE"PLUMBING"
HDL_POWER"GND";
"A\NAC"8;
%"GND"
"1","(-3075,1550)","0","mstr_symbols","I35";
;
SIZE"1B"
CDS_LIB"mstr_symbols"
VOLTAGE"0"
ROOM"PVCCIN_CPU0_VR"
BODY_TYPE"PLUMBING"
HDL_POWER"GND";
"A\NAC"9;
%"GND"
"1","(-3550,3725)","0","mstr_symbols","I36";
;
VOLTAGE"0"
CDS_LIB"mstr_symbols"
SIZE"1B"
ROOM"PVCCIN_CPU0_VR"
BODY_TYPE"PLUMBING"
HDL_POWER"GND";
"A\NAC"10;
%"CAP_A"
"1","(-3550,3925)","0","dev_discrete","I37";
;
SEC_TYPE"0402V"
SEC"1"
CDS_SEC"1"
ROOM"PVCCIN_CPU0_VR"
CDS_LIB"dev_discrete"
CDS_LOCATION"C4D15"
PART_NUMBER"D97712-004"
VOLTAGE"6.3V"
TOLERANCE"10%"
LOCATION"C4D15"
VALUE"1.0UF"
MATERIAL"X6S"
PACK_TYPE"0402V";
"B"
$PN"2"10;
"A"
$PN"1"53;
%"GND"
"1","(-3950,3725)","0","mstr_symbols","I38";
;
CDS_LIB"mstr_symbols"
SIZE"1B"
VOLTAGE"0"
ROOM"PVCCIN_CPU0_VR"
BODY_TYPE"PLUMBING"
HDL_POWER"GND";
"A\NAC"11;
%"CAP_A"
"1","(-3950,3925)","0","dev_discrete","I39";
;
SEC_TYPE"0402V"
SEC"1"
ROOM"PVCCIN_CPU0_VR"
CDS_SEC"1"
CDS_LIB"dev_discrete"
CDS_LOCATION"C4D19"
PART_NUMBER"A36096-030"
LOCATION"C4D19"
VALUE"0.1UF"
TOLERANCE"10%"
PACK_TYPE"0402V"
VOLTAGE"16V"
MATERIAL"X7R";
"B"
$PN"2"11;
"A"
$PN"1"53;
%"RES"
"2","(-4250,4275)","0","mstr_discrete","I40";
;
CDS_SEC"1"
ROOM"PVCCIN_CPU0_VR"
CDS_LOCATION"R4D26"
SEC"1"
SEC_TYPE"0402"
CDS_LIB"mstr_discrete"
LOCATION"R4D26"
PART_NUMBER"G21497-005"
PACK_TYPE"0402"
MATERIAL"CHIP"
WATTAGE"1/16W"
VALUE"0.0"
TOLERANCE"5%";
"A"
$PN"1"1;
"B"
$PN"2"53;
%"GND"
"1","(-4400,575)","0","mstr_symbols","I48";
;
SIZE"1B"
VOLTAGE"0"
CDS_LIB"mstr_symbols"
ROOM"PVCCIN_CPU0_VR"
BODY_TYPE"PLUMBING"
HDL_POWER"GND";
"A\NAC"12;
%"GND"
"1","(-4725,575)","0","mstr_symbols","I50";
;
VOLTAGE"0"
SIZE"1B"
CDS_LIB"mstr_symbols"
ROOM"PVCCIN_CPU0_VR"
BODY_TYPE"PLUMBING"
HDL_POWER"GND";
"A\NAC"13;
%"PVCCIO_CPU0"
"1","(-5325,4825)","0","mstr_symbols","I51";
;
VOLTAGE"1.1V"
CDS_LIB"mstr_symbols"
BODY_TYPE"PLUMBING"
HDL_POWER"PVCCIO_CPU0";
"G\NAC"14;
%"RES"
"2","(-5650,4275)","0","mstr_discrete","I52";
;
CDS_SEC"1"
ROOM"PVCCIN_CPU0_VR"
CDS_LOCATION"R4E9"
SEC"1"
SEC_TYPE"0402"
CDS_LIB"mstr_discrete"
PART_NUMBER"G21796-047"
LOCATION"R4E9"
VALUE"49.9"
TOLERANCE"1%"
PACK_TYPE"0402"
MATERIAL"CHIP"
WATTAGE"1/16W";
"A"
$PN"1"14;
"B"
$PN"2"50;
%"VCC_CORE"
"1","(-6050,4825)","0","mstr_symbols","I53";
;
CDS_LIB"mstr_symbols"
HDL_POWER"VR_FET_SW_P12V_STBY_PVCCIN_CPU0";
"A"15;
%"RES"
"2","(-6050,4625)","0","mstr_discrete","I54";
;
CDS_SEC"1"
SEC_TYPE"0402"
SEC"1"
ROOM"PVCCIN_CPU0_VR"
CDS_LOCATION"R4D27"
CDS_LIB"mstr_discrete"
VALUE"100.0K"
LOCATION"R4D27"
TOLERANCE"1%"
WATTAGE"1/16W"
PART_NUMBER"G21796-160"
MATERIAL"CHIP"
PACK_TYPE"0402";
"A"
$PN"1"15;
"B"
$PN"2"52;
%"RES"
"2","(-6050,4200)","0","mstr_discrete","I55";
;
CDS_SEC"1"
ROOM"PVCCIN_CPU0_VR"
SEC"1"
SEC_TYPE"0402"
CDS_LOCATION"R4D32"
CDS_LIB"mstr_discrete"
LOCATION"R4D32"
WATTAGE"1/16W"
MATERIAL"CHIP"
TOLERANCE"1%"
VALUE"1.5K"
PART_NUMBER"G21796-003"
PACK_TYPE"0402";
"A"
$PN"1"52;
"B"
$PN"2"16;
%"RES"
"1","(-5400,3950)","0","mstr_discrete","I56";
;
CDS_SEC"1"
ROOM"PVCCIN_CPU0_VR"
SEC"1"
SEC_TYPE"0402"
CDS_LOCATION"R4E6"
CDS_LIB"mstr_discrete"
MATERIAL"CHIP"
PACK_TYPE"0402"
LOCATION"R4E6"
PART_NUMBER"G21796-009"
TOLERANCE"1%"
WATTAGE"1/16W"
VALUE"150.0";
"B"
$PN"2"49;
"A"
$PN"1"50;
%"GND"
"1","(-6050,3975)","0","mstr_symbols","I58";
;
ROOM"PVCCIN_CPU0_VR"
VOLTAGE"0"
SIZE"1B"
CDS_LIB"mstr_symbols"
BODY_TYPE"PLUMBING"
HDL_POWER"GND";
"A\NAC"16;
%"CAP"
"1","(-6300,4225)","2","mstr_discrete","I60";
;
CDS_SEC"1"
ROOM"PVCCIN_CPU0_VR"
SEC"1"
SEC_TYPE"0402LF"
CDS_LOCATION"C4D20"
CDS_LIB"mstr_discrete"
LOCATION"C4D20"
VALUE"1000PF"
TOLERANCE"10%"
VOLTAGE"50V"
MATERIAL"X7R"
PART_NUMBER"A36096-046"
PACK_TYPE"0402LF";
"A"
$PN"1"52;
"B"
$PN"2"17;
%"GND"
"1","(-6300,4000)","0","mstr_symbols","I61";
;
ROOM"PVCCIN_CPU0_VR"
VOLTAGE"0"
SIZE"1B"
CDS_LIB"mstr_symbols"
BODY_TYPE"PLUMBING"
HDL_POWER"GND";
"A\NAC"17;
%"CAP"
"1","(-5550,2075)","0","mstr_discrete","I64";
;
CDS_SEC"1"
NO_XNET_CONNECTION"1"
SEC_TYPE"0402LF"
SEC"1"
CDS_LIB"mstr_discrete"
CDS_LOCATION"C4D29"
ROOM"PVCCIN_CPU0_VR"
LOCATION"C4D29"
PART_NUMBER"A36096-050"
VALUE"220PF"
TOLERANCE"10%"
PACK_TYPE"0402LF"
VOLTAGE"50V"
MATERIAL"X7R";
"A"
$PN"1"41;
"B"
$PN"2"45;
%"CAP"
"1","(-5450,1275)","0","mstr_discrete","I66";
;
CDS_SEC"1"
SEC_TYPE"0402LF"
SEC"1"
CDS_LOCATION"C4D17"
ROOM"PVCCIN_CPU0_VR"
CDS_LIB"mstr_discrete"
PART_NUMBER"A36096-050"
TOLERANCE"10%"
MATERIAL"X7R"
LOCATION"C4D17"
VALUE"220PF"
PACK_TYPE"0402LF"
VOLTAGE"50V";
"A"
$PN"1"44;
"B"
$PN"2"18;
%"GND"
"1","(-5450,1025)","0","mstr_symbols","I67";
;
CDS_LIB"mstr_symbols"
VOLTAGE"0"
ROOM"PVCCIN_CPU0_VR"
SIZE"1B"
BODY_TYPE"PLUMBING"
HDL_POWER"GND";
"A\NAC"18;
%"CAP"
"1","(-5125,1000)","2","mstr_discrete","I68";
;
CDS_SEC"1"
ROOM"PVCCIN_CPU0_VR"
SEC"1"
CDS_LOCATION"C4D18"
SEC_TYPE"0402LF"
CDS_LIB"mstr_discrete"
LOCATION"C4D18"
VALUE"220PF"
TOLERANCE"10%"
VOLTAGE"50V"
MATERIAL"X7R"
PACK_TYPE"0402LF"
PART_NUMBER"A36096-050";
"A"
$PN"1"30;
"B"
$PN"2"19;
%"GND"
"1","(-5125,775)","0","mstr_symbols","I69";
;
SIZE"1B"
VOLTAGE"0"
CDS_LIB"mstr_symbols"
ROOM"PVCCIN_CPU0_VR"
BODY_TYPE"PLUMBING"
HDL_POWER"GND";
"A\NAC"19;
%"CAP"
"1","(-6450,2375)","0","mstr_discrete","I70";
;
CDS_SEC"1"
SEC_TYPE"0402LF"
SEC"1"
ROOM"PVCCIN_CPU0_VR"
CDS_LOCATION"C4D45"
CDS_LIB"mstr_discrete"
PART_NUMBER"A36096-050"
TOLERANCE"10%"
NO_XNET_CONNECTION"1"
MATERIAL"X7R"
LOCATION"C4D45"
VALUE"220PF"
PACK_TYPE"0402LF"
VOLTAGE"50V";
"A"
$PN"1"29;
"B"
$PN"2"46;
%"RES"
"1","(-2400,2725)","0","mstr_discrete","I98";
;
CDS_SEC"1"
ROOM"PVCCIN_CPU0_VR"
SEC"1"
SEC_TYPE"0402"
CDS_LIB"mstr_discrete"
CDS_LOCATION"R4D66"
PART_NUMBER"G21497-005"
PACK_TYPE"0402"
TOLERANCE"5%"
LOCATION"R4D66"
MATERIAL"CHIP"
VALUE"0.0"
WATTAGE"1/16W";
"B"
$PN"2"77;
"A"
$PN"1"54;
END.
